# T6G (Grand Teton) — schematic parts with pin connectivity, parts 8082–8082 of 8303; source: Cadence DE-HDL packaged netlist (pstxprt.dat, pstxnet.dat, pstchip.dat)

U26  GENOA_SP5  SOCKET6096_13568-001 IO  pkg SOCKET6096_93-4X120-45XA  page 37  (pins 3361-3696 of 6096)
  CH57  VSS_CH57  POWER  = GND
  CH58  MDB_DATA7  BI  = M_D_CPU1_SB_DQ<7>
  CH59  VSS_CH59  POWER  = GND
  CH60  MDB_DATA8  BI  = M_D_CPU1_SB_DQ<8>
  CH61  VSS_CH61  POWER  = GND
  CH62  MBB_DATA7  BI  = M_B_CPU1_SB_DQ<7>
  CH63  MBB_DATA8  BI  = M_B_CPU1_SB_DQ<8>
  CH64  VSS_CH64  POWER  = GND
  CH65  MFB_DATA7  BI  = M_F_CPU1_SB_DQ<7>
  CH66  VSS_CH66  POWER  = GND
  CH67  MFB_DATA8  BI  = M_F_CPU1_SB_DQ<8>
  CH68  VSS_CH68  POWER  = GND
  CH69  MEB_DATA7  BI  = M_E_CPU1_SB_DQ<7>
  CH70  MEB_DATA8  BI  = M_E_CPU1_SB_DQ<8>
  CH71  VSS_CH71  POWER  = GND
  CH72  MAB_DATA7  BI  = M_A_CPU1_SB_DQ<7>
  CH73  VSS_CH73  POWER  = GND
  CH74  MAB_DATA8  BI  = M_A_CPU1_SB_DQ<8>
  CJ1  VSS_CJ1  POWER  = GND
  CJ2  MGB_DATA10  BI  = M_G_CPU1_SB_DQ<10>
  CJ3  MGB_DATA9  BI  = M_G_CPU1_SB_DQ<9>
  CJ4  VSS_CJ4  POWER  = GND
  CJ5  MKB_DATA10  BI  = M_K_CPU1_SB_DQ<10>
  CJ6  VSS_CJ6  POWER  = GND
  CJ7  MKB_DATA9  BI  = M_K_CPU1_SB_DQ<9>
  CJ8  VSS_CJ8  POWER  = GND
  CJ9  MLB_DATA10  BI  = M_L_CPU1_SB_DQ<10>
  CJ10  MLB_DATA9  BI  = M_L_CPU1_SB_DQ<9>
  CJ11  VSS_CJ11  POWER  = GND
  CJ12  MHB_DATA10  BI  = M_H_CPU1_SB_DQ<10>
  CJ13  VSS_CJ13  POWER  = GND
  CJ14  MHB_DATA9  BI  = M_H_CPU1_SB_DQ<9>
  CJ15  VSS_CJ15  POWER  = GND
  CJ16  MJB_DATA10  BI  = M_J_CPU1_SB_DQ<10>
  CJ17  MJB_DATA9  BI  = M_J_CPU1_SB_DQ<9>
  CJ18  VSS_CJ18  POWER  = GND
  CJ19  MIB_DATA10  BI  = M_I_CPU1_SB_DQ<10>
  CJ20  VSS_CJ20  POWER  = GND
  CJ21  MIB_DATA9  BI  = M_I_CPU1_SB_DQ<9>
  CJ22  VDD_11_S3_CJ22  POWER  = PVDD11_S3_P1
  CJ23  VSS_CJ23  POWER  = GND
  CJ24  TEST47_CCD1  TRI  = TP_CPU1_TEST47_CCD1
  CJ25  TEST5_CCD5  TRI  = TP_CPU1_TEST5_CCD5
  CJ26  TEST4_CCD5  TRI  = TP_CPU1_TEST4_CCD5
  CJ27  TEST5_CCD1  TRI  = TP_CPU1_TEST5_CCD1
  CJ28  TEST4_CCD1  TRI  = TP_CPU1_TEST4_CCD1
  CJ29  TEST6_X3D1  OUT  = TP_CPU1_TEST6_X3D1
  CJ30  TEST6_CCD1  OUT  = TP_CPU1_TEST6_CCD1
  CJ31  VSS_CJ31  POWER  = GND
  CJ32  P3_TXN4  OUT  = P5E_CPU1_P3_TX_DN<4>
  CJ33  P3_TXP4  OUT  = P5E_CPU1_P3_TX_DP<4>
  CJ34  VSS_CJ34  POWER  = GND
  CJ35  VSS_CJ35  POWER  = GND
  CJ36  VSS_CJ36  POWER  = GND
  CJ40  VSS_CJ40  POWER  = GND
  CJ41  VSS_CJ41  POWER  = GND
  CJ42  VSS_CJ42  POWER  = GND
  CJ43  P1_RXP11  IN  = P5E_CPU1_P1_RX_DP<11>
  CJ44  P1_RXN11  IN  = P5E_CPU1_P1_RX_DN<11>
  CJ45  VSS_CJ45  POWER  = GND
  CJ46  TEST6_CCD2  OUT  = TP_CPU1_TEST6_CCD2
  CJ47  TEST4_CCD10  TRI  = TP_CPU1_TEST4_CCD10
  CJ48  TEST4_CCD2  TRI  = TP_CPU1_TEST4_CCD2
  CJ49  TEST5_CCD2  TRI  = TP_CPU1_TEST5_CCD2
  CJ50  TEST4_CCD6  TRI  = TP_CPU1_TEST4_CCD6
  CJ51  TEST5_CCD6  TRI  = TP_CPU1_TEST5_CCD6
  CJ52  TEST6_X3D3  OUT  = TP_CPU1_TEST6_X3D3
  CJ53  TEST6_X3D5  OUT  = TP_CPU1_TEST6_X3D5
  CJ54  VDDIO_CJ54  POWER  = PVDDIO_P1
  CJ55  MCB_DATA9  BI  = M_C_CPU1_SB_DQ<9>
  CJ56  VSS_CJ56  POWER  = GND
  CJ57  MCB_DATA10  BI  = M_C_CPU1_SB_DQ<10>
  CJ58  VSS_CJ58  POWER  = GND
  CJ59  MDB_DATA9  BI  = M_D_CPU1_SB_DQ<9>
  CJ60  MDB_DATA10  BI  = M_D_CPU1_SB_DQ<10>
  CJ61  VSS_CJ61  POWER  = GND
  CJ62  MBB_DATA9  BI  = M_B_CPU1_SB_DQ<9>
  CJ63  VSS_CJ63  POWER  = GND
  CJ64  MBB_DATA10  BI  = M_B_CPU1_SB_DQ<10>
  CJ65  VSS_CJ65  POWER  = GND
  CJ66  MFB_DATA9  BI  = M_F_CPU1_SB_DQ<9>
  CJ67  MFB_DATA10  BI  = M_F_CPU1_SB_DQ<10>
  CJ68  VSS_CJ68  POWER  = GND
  CJ69  MEB_DATA9  BI  = M_E_CPU1_SB_DQ<9>
  CJ70  VSS_CJ70  POWER  = GND
  CJ71  MEB_DATA10  BI  = M_E_CPU1_SB_DQ<10>
  CJ72  VSS_CJ72  POWER  = GND
  CJ73  MAB_DATA9  BI  = M_A_CPU1_SB_DQ<9>
  CJ74  MAB_DATA10  BI  = M_A_CPU1_SB_DQ<10>
  CJ75  VSS_CJ75  POWER  = GND
  CK2  MGB_DQS_H1  BI  = M_G_CPU1_SB_DQS_DP<1>
  CK3  VSS_CK3  POWER  = GND
  CK4  MGB_DATA11  BI  = M_G_CPU1_SB_DQ<11>
  CK5  VDD_11_S3_CK5  POWER  = PVDD11_S3_P1
  CK6  MKB_DQS_H1  BI  = M_K_CPU1_SB_DQS_DP<1>
  CK7  MKB_DATA11  BI  = M_K_CPU1_SB_DQ<11>
  CK8  VSS_CK8  POWER  = GND
  CK9  MLB_DQS_H1  BI  = M_L_CPU1_SB_DQS_DP<1>
  CK10  VSS_CK10  POWER  = GND
  CK11  MLB_DATA11  BI  = M_L_CPU1_SB_DQ<11>
  CK12  VDD_11_S3_CK12  POWER  = PVDD11_S3_P1
  CK13  MHB_DQS_H1  BI  = M_H_CPU1_SB_DQS_DP<1>
  CK14  MHB_DATA11  BI  = M_H_CPU1_SB_DQ<11>
  CK15  VSS_CK15  POWER  = GND
  CK16  MJB_DQS_H1  BI  = M_J_CPU1_SB_DQS_DP<1>
  CK17  VSS_CK17  POWER  = GND
  CK18  MJB_DATA11  BI  = M_J_CPU1_SB_DQ<11>
  CK19  VDD_11_S3_CK19  POWER  = PVDD11_S3_P1
  CK20  MIB_DQS_H1  BI  = M_I_CPU1_SB_DQS_DP<1>
  CK21  MIB_DATA11  BI  = M_I_CPU1_SB_DQ<11>
  CK22  VSS_CK22  POWER  = GND
  CK23  VSS_CK23  POWER  = GND
  CK24  VSS_CK24  POWER  = GND
  CK25  VSS_CK25  POWER  = GND
  CK26  VSS_CK26  POWER  = GND
  CK27  VSS_CK27  POWER  = GND
  CK28  VSS_CK28  POWER  = GND
  CK29  TEST5_CCD9  TRI  = TP_CPU1_TEST5_CCD9
  CK30  TEST4_CCD9  TRI  = TP_CPU1_TEST4_CCD9
  CK31  VSS_CK31  POWER  = GND
  CK32  VSS_CK32  POWER  = GND
  CK33  VSS_CK33  POWER  = GND
  CK34  VSS_CK34  POWER  = GND
  CK35  VDDCR_CPU1_CK35  POWER  = PVDDCR_CPU1_P1
  CK36  VDDCR_CPU1_CK36  POWER  = PVDDCR_CPU1_P1
  CK37  VSS_CK37  POWER  = GND
  CK39  VSS_CK39  POWER  = GND
  CK40  VDDCR_CPU1_CK40  POWER  = PVDDCR_CPU1_P1
  CK41  VDDCR_CPU1_CK41  POWER  = PVDDCR_CPU1_P1
  CK42  VSS_CK42  POWER  = GND
  CK43  VSS_CK43  POWER  = GND
  CK44  VSS_CK44  POWER  = GND
  CK45  VSS_CK45  POWER  = GND
  CK46  TEST47_CCD2  TRI  = TP_CPU1_TEST47_CCD2
  CK47  TEST5_CCD10  TRI  = TP_CPU1_TEST5_CCD10
  CK48  VSS_CK48  POWER  = GND
  CK49  VSS_CK49  POWER  = GND
  CK50  VSS_CK50  POWER  = GND
  CK51  VSS_CK51  POWER  = GND
  CK52  VSS_CK52  POWER  = GND
  CK53  VSS_CK53  POWER  = GND
  CK54  VSS_CK54  POWER  = GND
  CK55  MCB_DATA11  BI  = M_C_CPU1_SB_DQ<11>
  CK56  MCB_DQS_H1  BI  = M_C_CPU1_SB_DQS_DP<1>
  CK57  VDDIO_CK57  POWER  = PVDDIO_P1
  CK58  MDB_DATA11  BI  = M_D_CPU1_SB_DQ<11>
  CK59  VSS_CK59  POWER  = GND
  CK60  MDB_DQS_H1  BI  = M_D_CPU1_SB_DQS_DP<1>
  CK61  VSS_CK61  POWER  = GND
  CK62  MBB_DATA11  BI  = M_B_CPU1_SB_DQ<11>
  CK63  MBB_DQS_H1  BI  = M_B_CPU1_SB_DQS_DP<1>
  CK64  VDDIO_CK64  POWER  = PVDDIO_P1
  CK65  MFB_DATA11  BI  = M_F_CPU1_SB_DQ<11>
  CK66  VSS_CK66  POWER  = GND
  CK67  MFB_DQS_H1  BI  = M_F_CPU1_SB_DQS_DP<1>
  CK68  VSS_CK68  POWER  = GND
  CK69  MEB_DATA11  BI  = M_E_CPU1_SB_DQ<11>
  CK70  MEB_DQS_H1  BI  = M_E_CPU1_SB_DQS_DP<1>
  CK71  VDDIO_CK71  POWER  = PVDDIO_P1
  CK72  MAB_DATA11  BI  = M_A_CPU1_SB_DQ<11>
  CK73  VSS_CK73  POWER  = GND
  CK74  MAB_DQS_H1  BI  = M_A_CPU1_SB_DQS_DP<1>
  CL1  VSS_CL1  POWER  = GND
  CL2  MGB_DQS_L1  BI  = M_G_CPU1_SB_DQS_DN<1>
  CL3  MGB_DQS_L6  BI  = M_G_CPU1_SB_DQS_DN<6>
  CL4  VSS_CL4  POWER  = GND
  CL5  MKB_DQS_L1  BI  = M_K_CPU1_SB_DQS_DN<1>
  CL6  VSS_CL6  POWER  = GND
  CL7  MKB_DQS_L6  BI  = M_K_CPU1_SB_DQS_DN<6>
  CL8  VSS_CL8  POWER  = GND
  CL9  MLB_DQS_L1  BI  = M_L_CPU1_SB_DQS_DN<1>
  CL10  MLB_DQS_L6  BI  = M_L_CPU1_SB_DQS_DN<6>
  CL11  VSS_CL11  POWER  = GND
  CL12  MHB_DQS_L1  BI  = M_H_CPU1_SB_DQS_DN<1>
  CL13  VSS_CL13  POWER  = GND
  CL14  MHB_DQS_L6  BI  = M_H_CPU1_SB_DQS_DN<6>
  CL15  VSS_CL15  POWER  = GND
  CL16  MJB_DQS_L1  BI  = M_J_CPU1_SB_DQS_DN<1>
  CL17  MJB_DQS_L6  BI  = M_J_CPU1_SB_DQS_DN<6>
  CL18  VSS_CL18  POWER  = GND
  CL19  MIB_DQS_L1  BI  = M_I_CPU1_SB_DQS_DN<1>
  CL20  VSS_CL20  POWER  = GND
  CL21  MIB_DQS_L6  BI  = M_I_CPU1_SB_DQS_DN<6>
  CL22  VSS_CL22  POWER  = GND
  CL23  P2_RXP13  IN  = P5E_CPU1_P2_RX_DP<13>
  CL24  P2_RXN13  IN  = P5E_CPU1_P2_RX_DN<13>
  CL25  VSS_CL25  POWER  = GND
  CL26  P2_RXP9  IN  = P5E_CPU1_P2_RX_DP<9>
  CL27  P2_RXN9  IN  = P5E_CPU1_P2_RX_DN<9>
  CL28  VSS_CL28  POWER  = GND
  CL29  VDDCR_CPU1_CL29  POWER  = PVDDCR_CPU1_P1
  CL30  VDDCR_CPU1_CL30  POWER  = PVDDCR_CPU1_P1
  CL31  VSS_CL31  POWER  = GND
  CL32  VDDCR_CPU1_CL32  POWER  = PVDDCR_CPU1_P1
  CL33  VDDCR_CPU1_CL33  POWER  = PVDDCR_CPU1_P1
  CL34  VSS_CL34  POWER  = GND
  CL35  VSS_CL35  POWER  = GND
  CL36  VSS_CL36  POWER  = GND
  CL40  VSS_CL40  POWER  = GND
  CL41  VSS_CL41  POWER  = GND
  CL42  VSS_CL42  POWER  = GND
  CL43  VDDCR_CPU1_CL43  POWER  = PVDDCR_CPU1_P1
  CL44  VDDCR_CPU1_CL44  POWER  = PVDDCR_CPU1_P1
  CL45  VSS_CL45  POWER  = GND
  CL46  VDDCR_CPU1_CL46  POWER  = PVDDCR_CPU1_P1
  CL47  VDDCR_CPU1_CL47  POWER  = PVDDCR_CPU1_P1
  CL48  VSS_CL48  POWER  = GND
  CL49  \p0_txn6||sata06_txn\  OUT  = P5E_CPU1_P0_TX_DN<6>
  CL50  \p0_txp6||sata06_txp\  OUT  = P5E_CPU1_P0_TX_DP<6>
  CL51  VSS_CL51  POWER  = GND
  CL52  \p0_txn2||sata02_txn\  OUT  = P5E_CPU1_P0_TX_DN<2>
  CL53  \p0_txp2||sata02_txp\  OUT  = P5E_CPU1_P0_TX_DP<2>
  CL54  VSS_CL54  POWER  = GND
  CL55  MCB_DQS_L6  BI  = M_C_CPU1_SB_DQS_DN<6>
  CL56  VSS_CL56  POWER  = GND
  CL57  MCB_DQS_L1  BI  = M_C_CPU1_SB_DQS_DN<1>
  CL58  VSS_CL58  POWER  = GND
  CL59  MDB_DQS_L6  BI  = M_D_CPU1_SB_DQS_DN<6>
  CL60  MDB_DQS_L1  BI  = M_D_CPU1_SB_DQS_DN<1>
  CL61  VSS_CL61  POWER  = GND
  CL62  MBB_DQS_L6  BI  = M_B_CPU1_SB_DQS_DN<6>
  CL63  VSS_CL63  POWER  = GND
  CL64  MBB_DQS_L1  BI  = M_B_CPU1_SB_DQS_DN<1>
  CL65  VSS_CL65  POWER  = GND
  CL66  MFB_DQS_L6  BI  = M_F_CPU1_SB_DQS_DN<6>
  CL67  MFB_DQS_L1  BI  = M_F_CPU1_SB_DQS_DN<1>
  CL68  VSS_CL68  POWER  = GND
  CL69  MEB_DQS_L6  BI  = M_E_CPU1_SB_DQS_DN<6>
  CL70  VSS_CL70  POWER  = GND
  CL71  MEB_DQS_L1  BI  = M_E_CPU1_SB_DQS_DN<1>
  CL72  VSS_CL72  POWER  = GND
  CL73  MAB_DQS_L6  BI  = M_A_CPU1_SB_DQS_DN<6>
  CL74  MAB_DQS_L1  BI  = M_A_CPU1_SB_DQS_DN<1>
  CL75  VSS_CL75  POWER  = GND
  CM2  MGB_DATA12  BI  = M_G_CPU1_SB_DQ<12>
  CM3  VSS_CM3  POWER  = GND
  CM4  MGB_DQS_H6  BI  = M_G_CPU1_SB_DQS_DP<6>
  CM5  VSS_CM5  POWER  = GND
  CM6  MKB_DATA12  BI  = M_K_CPU1_SB_DQ<12>
  CM7  MKB_DQS_H6  BI  = M_K_CPU1_SB_DQS_DP<6>
  CM8  VSS_CM8  POWER  = GND
  CM9  MLB_DATA12  BI  = M_L_CPU1_SB_DQ<12>
  CM10  VSS_CM10  POWER  = GND
  CM11  MLB_DQS_H6  BI  = M_L_CPU1_SB_DQS_DP<6>
  CM12  VSS_CM12  POWER  = GND
  CM13  MHB_DATA12  BI  = M_H_CPU1_SB_DQ<12>
  CM14  MHB_DQS_H6  BI  = M_H_CPU1_SB_DQS_DP<6>
  CM15  VSS_CM15  POWER  = GND
  CM16  MJB_DATA12  BI  = M_J_CPU1_SB_DQ<12>
  CM17  VSS_CM17  POWER  = GND
  CM18  MJB_DQS_H6  BI  = M_J_CPU1_SB_DQS_DP<6>
  CM19  VSS_CM19  POWER  = GND
  CM20  MIB_DATA12  BI  = M_I_CPU1_SB_DQ<12>
  CM21  MIB_DQS_H6  BI  = M_I_CPU1_SB_DQS_DP<6>
  CM22  VDD_11_S3_CM22  POWER  = PVDD11_S3_P1
  CM23  VSS_CM23  POWER  = GND
  CM24  VSS_CM24  POWER  = GND
  CM25  VSS_CM25  POWER  = GND
  CM26  VSS_CM26  POWER  = GND
  CM27  VSS_CM27  POWER  = GND
  CM28  VSS_CM28  POWER  = GND
  CM29  VSS_CM29  POWER  = GND
  CM30  VSS_CM30  POWER  = GND
  CM31  VSS_CM31  POWER  = GND
  CM32  VSS_CM32  POWER  = GND
  CM33  VSS_CM33  POWER  = GND
  CM34  VSS_CM34  POWER  = GND
  CM35  P2_RXP0  IN  = P5E_CPU1_P2_RX_DP<0>
  CM36  P2_RXN0  IN  = P5E_CPU1_P2_RX_DN<0>
  CM37  VSS_CM37  POWER  = GND
  CM39  VSS_CM39  POWER  = GND
  CM40  \p0_txn15||sata17_txn\  OUT  = P5E_CPU1_P0_TX_DN<15>
  CM41  \p0_txp15||sata17_txp\  OUT  = P5E_CPU1_P0_TX_DP<15>
  CM42  VSS_CM42  POWER  = GND
  CM43  VSS_CM43  POWER  = GND
  CM44  VSS_CM44  POWER  = GND
  CM45  VSS_CM45  POWER  = GND
  CM46  VSS_CM46  POWER  = GND
  CM47  VSS_CM47  POWER  = GND
  CM48  VSS_CM48  POWER  = GND
  CM49  VSS_CM49  POWER  = GND
  CM50  VSS_CM50  POWER  = GND
  CM51  VSS_CM51  POWER  = GND
  CM52  VSS_CM52  POWER  = GND
  CM53  VSS_CM53  POWER  = GND
  CM54  VDDIO_CM54  POWER  = PVDDIO_P1
  CM55  MCB_DQS_H6  BI  = M_C_CPU1_SB_DQS_DP<6>
  CM56  MCB_DATA12  BI  = M_C_CPU1_SB_DQ<12>
  CM57  VSS_CM57  POWER  = GND
  CM58  MDB_DQS_H6  BI  = M_D_CPU1_SB_DQS_DP<6>
  CM59  VSS_CM59  POWER  = GND
  CM60  MDB_DATA12  BI  = M_D_CPU1_SB_DQ<12>
  CM61  VSS_CM61  POWER  = GND
  CM62  MBB_DQS_H6  BI  = M_B_CPU1_SB_DQS_DP<6>
  CM63  MBB_DATA12  BI  = M_B_CPU1_SB_DQ<12>
  CM64  VSS_CM64  POWER  = GND
  CM65  MFB_DQS_H6  BI  = M_F_CPU1_SB_DQS_DP<6>
  CM66  VSS_CM66  POWER  = GND
  CM67  MFB_DATA12  BI  = M_F_CPU1_SB_DQ<12>
  CM68  VSS_CM68  POWER  = GND
  CM69  MEB_DQS_H6  BI  = M_E_CPU1_SB_DQS_DP<6>
  CM70  MEB_DATA12  BI  = M_E_CPU1_SB_DQ<12>
  CM71  VSS_CM71  POWER  = GND
  CM72  MAB_DQS_H6  BI  = M_A_CPU1_SB_DQS_DP<6>
  CM73  VSS_CM73  POWER  = GND
  CM74  MAB_DATA12  BI  = M_A_CPU1_SB_DQ<12>
  CN1  VSS_CN1  POWER  = GND
  CN2  MGB_DATA14  BI  = M_G_CPU1_SB_DQ<14>
  CN3  MGB_DATA13  BI  = M_G_CPU1_SB_DQ<13>
  CN4  VDD_11_S3_CN4  POWER  = PVDD11_S3_P1
  CN5  MKB_DATA14  BI  = M_K_CPU1_SB_DQ<14>
  CN6  VSS_CN6  POWER  = GND
  CN7  MKB_DATA13  BI  = M_K_CPU1_SB_DQ<13>
  CN8  VSS_CN8  POWER  = GND
  CN9  MLB_DATA14  BI  = M_L_CPU1_SB_DQ<14>
  CN10  MLB_DATA13  BI  = M_L_CPU1_SB_DQ<13>
  CN11  VDD_11_S3_CN11  POWER  = PVDD11_S3_P1
  CN12  MHB_DATA14  BI  = M_H_CPU1_SB_DQ<14>
  CN13  VSS_CN13  POWER  = GND
  CN14  MHB_DATA13  BI  = M_H_CPU1_SB_DQ<13>
  CN15  VSS_CN15  POWER  = GND
  CN16  MJB_DATA14  BI  = M_J_CPU1_SB_DQ<14>
  CN17  MJB_DATA13  BI  = M_J_CPU1_SB_DQ<13>
  CN18  VDD_11_S3_CN18  POWER  = PVDD11_S3_P1
  CN19  MIB_DATA14  BI  = M_I_CPU1_SB_DQ<14>
  CN20  VSS_CN20  POWER  = GND
  CN21  MIB_DATA13  BI  = M_I_CPU1_SB_DQ<13>
  CN22  VSS_CN22  POWER  = GND
  CN23  P2_RXP15  IN  = P5E_CPU1_P2_RX_DP<15>
  CN24  P2_RXN15  IN  = P5E_CPU1_P2_RX_DN<15>
  CN25  VSS_CN25  POWER  = GND
  CN26  P2_RXP12  IN  = P5E_CPU1_P2_RX_DP<12>
  CN27  P2_RXN12  IN  = P5E_CPU1_P2_RX_DN<12>
  CN28  VSS_CN28  POWER  = GND
  CN29  P2_RXP6  IN  = P5E_CPU1_P2_RX_DP<6>
  CN30  P2_RXN6  IN  = P5E_CPU1_P2_RX_DN<6>
